(kicad_pcb
	(version 20221018)
	(generator pcbnew)
	(general
    (thickness 1.62)
  )
	(paper "A4")
	(title_block
    (title "ECP5 - Datacenter Secure Control Module (DC-SCM)")
    (date "2024-07-01")
    (rev "1.2.1")
		(comment 9 "footprints 336-343 of 506")
	)
	(layers
    (0 "F.Cu" signal)
    (1 "In1.Cu" power)
    (2 "In2.Cu" signal)
    (3 "In3.Cu" power)
    (4 "In4.Cu" power)
    (5 "In5.Cu" signal)
    (6 "In6.Cu" power)
    (31 "B.Cu" signal)
    (32 "B.Adhes" user "B.Adhesive")
    (33 "F.Adhes" user "F.Adhesive")
    (34 "B.Paste" user)
    (35 "F.Paste" user)
    (36 "B.SilkS" user "B.Silkscreen")
    (37 "F.SilkS" user "F.Silkscreen")
    (38 "B.Mask" user)
    (39 "F.Mask" user)
    (40 "Dwgs.User" user "User.Drawings")
    (41 "Cmts.User" user "User.Comments")
    (42 "Eco1.User" user "User.Eco1")
    (43 "Eco2.User" user "User.Eco2")
    (44 "Edge.Cuts" user)
    (45 "Margin" user)
    (46 "B.CrtYd" user "B.Courtyard")
    (47 "F.CrtYd" user "F.Courtyard")
    (48 "B.Fab" user)
    (49 "F.Fab" user)
  )
	(footprint "antmicro-footprints:C_0402_1005Metric" (layer "B.Cu")
    (at 97.6 121.27857 180)
    (descr "Capacitor SMD 0402")
    (tags "capacitor SMD 0402")
    (property "Author" "Antmicro")
    (property "Dielectric" "")
    (property "License" "Apache-2.0")
    (property "MPN" "GRM155R61A475MEAAD")
    (property "Manufacturer" "Murata")
    (property "Public" "False")
    (property "Sheetfile" "fpga-banks.kicad_sch")
    (property "Sheetname" "FPGA banks")
    (property "Val" "4u7")
    (property "Voltage" "")
    (property "ki_description" "SMD Multilayer Ceramic Capacitor, 4.7 µF, 10 V, 0402 [1005 Metric], ± 20%, X5R, GRM Series")
    (property "ki_keywords" "0402, SMT, CAPACITOR, PASSIVE")
    (attr smd)
    (fp_text reference "C230" (at 2.4 0.22857) (layer "B.SilkS")
        (effects (font (size 0.7 0.7) (thickness 0.127)) (justify mirror))
    )
    (fp_text value "C_4u7_0402" (at 0 -1.17) (layer "B.Fab")
        (effects (font (size 1 1) (thickness 0.15)) (justify mirror))
    )
    (fp_text user "License: Apache-2.0" (at -0.939 -5.799) (layer "B.Fab") hide
        (effects (font (size 0.7 0.7) (thickness 0.15)) (justify left bottom mirror))
    )
    (fp_text user "${REFERENCE}" (at 0 0) (layer "B.Fab")
        (effects (font (size 0.25 0.25) (thickness 0.04)) (justify mirror))
    )
    (fp_text user "Author: Antmicro" (at -0.939 -3.399) (layer "B.Fab") hide
        (effects (font (size 0.7 0.7) (thickness 0.15)) (justify left bottom mirror))
    )
    (fp_rect (start -0.925 0.47) (end 0.925 -0.47)
      (stroke (width 0.05) (type default)) (fill none) (layer "B.CrtYd"))
    (fp_line (start -0.494 -0.248) (end -0.494 0.25)
      (stroke (width 0.15) (type solid)) (layer "B.Fab"))
    (fp_line (start -0.494 0.25) (end 0.504 0.25)
      (stroke (width 0.15) (type solid)) (layer "B.Fab"))
    (fp_line (start 0.504 -0.248) (end -0.494 -0.248)
      (stroke (width 0.15) (type solid)) (layer "B.Fab"))
    (fp_line (start 0.504 0.25) (end 0.504 -0.248)
      (stroke (width 0.15) (type solid)) (layer "B.Fab"))
    (pad "1" smd roundrect (at -0.48 0 180) (size 0.59 0.64) (layers "B.Cu" "B.Paste" "B.Mask") (roundrect_rratio 0.25)
      (net 3 "VCC1V35") (pintype "passive"))
    (pad "2" smd roundrect (at 0.48 0 180) (size 0.59 0.64) (layers "B.Cu" "B.Paste" "B.Mask") (roundrect_rratio 0.25)
      (net 1 "GND") (pintype "passive"))
  )
	(footprint "antmicro-footprints:C_0402_1005Metric" (layer "B.Cu")
    (at 97.6 122.314284)
    (descr "Capacitor SMD 0402")
    (tags "capacitor SMD 0402")
    (property "Author" "Antmicro")
    (property "Dielectric" "")
    (property "License" "Apache-2.0")
    (property "MPN" "C1005X5R1E474M050BB")
    (property "Manufacturer" "TDK")
    (property "Public" "False")
    (property "Sheetfile" "fpga-banks.kicad_sch")
    (property "Sheetname" "FPGA banks")
    (property "Val" "470n")
    (property "Voltage" "")
    (property "ki_description" "SMD Multilayer Ceramic Capacitor, 0.47 µF, 25 V, 0402 [1005 Metric], ± 20%, X5R, C")
    (property "ki_keywords" "0402, SMT, CAPACITOR, PASSIVE, CERAMIC, MLCC")
    (attr smd)
    (fp_text reference "C231" (at -2.16 -0.209284) (layer "B.SilkS")
        (effects (font (size 0.7 0.7) (thickness 0.127)) (justify mirror))
    )
    (fp_text value "C_470n_0402" (at 0 -1.17) (layer "B.Fab")
        (effects (font (size 1 1) (thickness 0.15)) (justify mirror))
    )
    (fp_text user "${REFERENCE}" (at 0 0) (layer "B.Fab")
        (effects (font (size 0.25 0.25) (thickness 0.04)) (justify mirror))
    )
    (fp_text user "License: Apache-2.0" (at -0.939 -5.799 180) (layer "B.Fab") hide
        (effects (font (size 0.7 0.7) (thickness 0.15)) (justify left bottom mirror))
    )
    (fp_text user "Author: Antmicro" (at -0.939 -3.399 180) (layer "B.Fab") hide
        (effects (font (size 0.7 0.7) (thickness 0.15)) (justify left bottom mirror))
    )
    (fp_rect (start -0.925 0.47) (end 0.925 -0.47)
      (stroke (width 0.05) (type default)) (fill none) (layer "B.CrtYd"))
    (fp_line (start -0.494 -0.248) (end -0.494 0.25)
      (stroke (width 0.15) (type solid)) (layer "B.Fab"))
    (fp_line (start -0.494 0.25) (end 0.504 0.25)
      (stroke (width 0.15) (type solid)) (layer "B.Fab"))
    (fp_line (start 0.504 -0.248) (end -0.494 -0.248)
      (stroke (width 0.15) (type solid)) (layer "B.Fab"))
    (fp_line (start 0.504 0.25) (end 0.504 -0.248)
      (stroke (width 0.15) (type solid)) (layer "B.Fab"))
    (pad "1" smd roundrect (at -0.48 0) (size 0.59 0.64) (layers "B.Cu" "B.Paste" "B.Mask") (roundrect_rratio 0.25)
      (net 1 "GND") (pintype "passive"))
    (pad "2" smd roundrect (at 0.48 0) (size 0.59 0.64) (layers "B.Cu" "B.Paste" "B.Mask") (roundrect_rratio 0.25)
      (net 3 "VCC1V35") (pintype "passive"))
  )
	(footprint "antmicro-footprints:C_0402_1005Metric" (layer "B.Cu")
    (at 99.5 122.6 -90)
    (descr "Capacitor SMD 0402")
    (tags "capacitor SMD 0402")
    (property "Author" "Antmicro")
    (property "Dielectric" "")
    (property "License" "Apache-2.0")
    (property "MPN" "C1005X5R1E474M050BB")
    (property "Manufacturer" "TDK")
    (property "Public" "False")
    (property "Sheetfile" "fpga-banks.kicad_sch")
    (property "Sheetname" "FPGA banks")
    (property "Val" "470n")
    (property "Voltage" "")
    (property "ki_description" "SMD Multilayer Ceramic Capacitor, 0.47 µF, 25 V, 0402 [1005 Metric], ± 20%, X5R, C")
    (property "ki_keywords" "0402, SMT, CAPACITOR, PASSIVE, CERAMIC, MLCC")
    (attr smd)
    (fp_text reference "C232" (at 22.5 -0.05 90) (layer "B.SilkS")
        (effects (font (size 0.7 0.7) (thickness 0.127)) (justify mirror))
    )
    (fp_text value "C_470n_0402" (at 0 -1.17 90) (layer "B.Fab")
        (effects (font (size 1 1) (thickness 0.15)) (justify mirror))
    )
    (fp_text user "${REFERENCE}" (at 0 0 90) (layer "B.Fab")
        (effects (font (size 0.25 0.25) (thickness 0.04)) (justify mirror))
    )
    (fp_text user "Author: Antmicro" (at -0.939 -3.399 90) (layer "B.Fab") hide
        (effects (font (size 0.7 0.7) (thickness 0.15)) (justify left bottom mirror))
    )
    (fp_text user "License: Apache-2.0" (at -0.939 -5.799 90) (layer "B.Fab") hide
        (effects (font (size 0.7 0.7) (thickness 0.15)) (justify left bottom mirror))
    )
    (fp_rect (start -0.925 0.47) (end 0.925 -0.47)
      (stroke (width 0.05) (type default)) (fill none) (layer "B.CrtYd"))
    (fp_line (start -0.494 -0.248) (end -0.494 0.25)
      (stroke (width 0.15) (type solid)) (layer "B.Fab"))
    (fp_line (start -0.494 0.25) (end 0.504 0.25)
      (stroke (width 0.15) (type solid)) (layer "B.Fab"))
    (fp_line (start 0.504 -0.248) (end -0.494 -0.248)
      (stroke (width 0.15) (type solid)) (layer "B.Fab"))
    (fp_line (start 0.504 0.25) (end 0.504 -0.248)
      (stroke (width 0.15) (type solid)) (layer "B.Fab"))
    (pad "1" smd roundrect (at -0.48 0 270) (size 0.59 0.64) (layers "B.Cu" "B.Paste" "B.Mask") (roundrect_rratio 0.25)
      (net 3 "VCC1V35") (pintype "passive"))
    (pad "2" smd roundrect (at 0.48 0 270) (size 0.59 0.64) (layers "B.Cu" "B.Paste" "B.Mask") (roundrect_rratio 0.25)
      (net 1 "GND") (pintype "passive"))
  )
	(footprint "antmicro-footprints:C_0402_1005Metric" (layer "B.Cu")
    (at 79.45 116.95 180)
    (descr "Capacitor SMD 0402")
    (tags "capacitor SMD 0402")
    (property "Author" "Antmicro")
    (property "Dielectric" "")
    (property "License" "Apache-2.0")
    (property "MPN" "C1005X5R1E474M050BB")
    (property "Manufacturer" "TDK")
    (property "Public" "False")
    (property "Sheetfile" "fpga-banks.kicad_sch")
    (property "Sheetname" "FPGA banks")
    (property "Val" "470n")
    (property "Voltage" "")
    (property "ki_description" "SMD Multilayer Ceramic Capacitor, 0.47 µF, 25 V, 0402 [1005 Metric], ± 20%, X5R, C")
    (property "ki_keywords" "0402, SMT, CAPACITOR, PASSIVE, CERAMIC, MLCC")
    (attr smd)
    (fp_text reference "C233" (at -0.08 0.995) (layer "B.SilkS")
        (effects (font (size 0.7 0.7) (thickness 0.127)) (justify mirror))
    )
    (fp_text value "C_470n_0402" (at 0 -1.17) (layer "B.Fab")
        (effects (font (size 1 1) (thickness 0.15)) (justify mirror))
    )
    (fp_text user "License: Apache-2.0" (at -0.939 -5.799) (layer "B.Fab") hide
        (effects (font (size 0.7 0.7) (thickness 0.15)) (justify left bottom mirror))
    )
    (fp_text user "${REFERENCE}" (at 0 0) (layer "B.Fab")
        (effects (font (size 0.25 0.25) (thickness 0.04)) (justify mirror))
    )
    (fp_text user "Author: Antmicro" (at -0.939 -3.399) (layer "B.Fab") hide
        (effects (font (size 0.7 0.7) (thickness 0.15)) (justify left bottom mirror))
    )
    (fp_rect (start -0.925 0.47) (end 0.925 -0.47)
      (stroke (width 0.05) (type default)) (fill none) (layer "B.CrtYd"))
    (fp_line (start -0.494 -0.248) (end -0.494 0.25)
      (stroke (width 0.15) (type solid)) (layer "B.Fab"))
    (fp_line (start -0.494 0.25) (end 0.504 0.25)
      (stroke (width 0.15) (type solid)) (layer "B.Fab"))
    (fp_line (start 0.504 -0.248) (end -0.494 -0.248)
      (stroke (width 0.15) (type solid)) (layer "B.Fab"))
    (fp_line (start 0.504 0.25) (end 0.504 -0.248)
      (stroke (width 0.15) (type solid)) (layer "B.Fab"))
    (pad "1" smd roundrect (at -0.48 0 180) (size 0.59 0.64) (layers "B.Cu" "B.Paste" "B.Mask") (roundrect_rratio 0.25)
      (net 3 "VCC1V35") (pintype "passive"))
    (pad "2" smd roundrect (at 0.48 0 180) (size 0.59 0.64) (layers "B.Cu" "B.Paste" "B.Mask") (roundrect_rratio 0.25)
      (net 1 "GND") (pintype "passive"))
  )
	(footprint "antmicro-footprints:C_0402_1005Metric" (layer "B.Cu")
    (at 97.6 124.65 180)
    (descr "Capacitor SMD 0402")
    (tags "capacitor SMD 0402")
    (property "Author" "Antmicro")
    (property "Dielectric" "")
    (property "License" "Apache-2.0")
    (property "MPN" "C1005X5R1E474M050BB")
    (property "Manufacturer" "TDK")
    (property "Public" "False")
    (property "Sheetfile" "fpga-banks.kicad_sch")
    (property "Sheetname" "FPGA banks")
    (property "Val" "470n")
    (property "Voltage" "")
    (property "ki_description" "SMD Multilayer Ceramic Capacitor, 0.47 µF, 25 V, 0402 [1005 Metric], ± 20%, X5R, C")
    (property "ki_keywords" "0402, SMT, CAPACITOR, PASSIVE, CERAMIC, MLCC")
    (attr smd)
    (fp_text reference "C234" (at 2.3 -0.2) (layer "B.SilkS")
        (effects (font (size 0.7 0.7) (thickness 0.127)) (justify mirror))
    )
    (fp_text value "C_470n_0402" (at 0 -1.17) (layer "B.Fab")
        (effects (font (size 1 1) (thickness 0.15)) (justify mirror))
    )
    (fp_text user "License: Apache-2.0" (at -0.939 -5.799) (layer "B.Fab") hide
        (effects (font (size 0.7 0.7) (thickness 0.15)) (justify left bottom mirror))
    )
    (fp_text user "Author: Antmicro" (at -0.939 -3.399) (layer "B.Fab") hide
        (effects (font (size 0.7 0.7) (thickness 0.15)) (justify left bottom mirror))
    )
    (fp_text user "${REFERENCE}" (at 0 0) (layer "B.Fab")
        (effects (font (size 0.25 0.25) (thickness 0.04)) (justify mirror))
    )
    (fp_rect (start -0.925 0.47) (end 0.925 -0.47)
      (stroke (width 0.05) (type default)) (fill none) (layer "B.CrtYd"))
    (fp_line (start -0.494 -0.248) (end -0.494 0.25)
      (stroke (width 0.15) (type solid)) (layer "B.Fab"))
    (fp_line (start -0.494 0.25) (end 0.504 0.25)
      (stroke (width 0.15) (type solid)) (layer "B.Fab"))
    (fp_line (start 0.504 -0.248) (end -0.494 -0.248)
      (stroke (width 0.15) (type solid)) (layer "B.Fab"))
    (fp_line (start 0.504 0.25) (end 0.504 -0.248)
      (stroke (width 0.15) (type solid)) (layer "B.Fab"))
    (pad "1" smd roundrect (at -0.48 0 180) (size 0.59 0.64) (layers "B.Cu" "B.Paste" "B.Mask") (roundrect_rratio 0.25)
      (net 3 "VCC1V35") (pintype "passive"))
    (pad "2" smd roundrect (at 0.48 0 180) (size 0.59 0.64) (layers "B.Cu" "B.Paste" "B.Mask") (roundrect_rratio 0.25)
      (net 1 "GND") (pintype "passive"))
  )
	(footprint "antmicro-footprints:C_0402_1005Metric" (layer "B.Cu")
    (at 104.4 113.2 90)
    (descr "Capacitor SMD 0402")
    (tags "capacitor SMD 0402")
    (property "Author" "Antmicro")
    (property "Dielectric" "")
    (property "License" "Apache-2.0")
    (property "MPN" "GRM155R61A475MEAAD")
    (property "Manufacturer" "Murata")
    (property "Public" "False")
    (property "Sheetfile" "fpga-banks.kicad_sch")
    (property "Sheetname" "FPGA banks")
    (property "Val" "4u7")
    (property "Voltage" "")
    (property "ki_description" "SMD Multilayer Ceramic Capacitor, 4.7 µF, 10 V, 0402 [1005 Metric], ± 20%, X5R, GRM Series")
    (property "ki_keywords" "0402, SMT, CAPACITOR, PASSIVE")
    (attr smd)
    (fp_text reference "C235" (at 5.25 0.05 90) (layer "B.SilkS")
        (effects (font (size 0.7 0.7) (thickness 0.127)) (justify mirror))
    )
    (fp_text value "C_4u7_0402" (at 0 -1.17 90) (layer "B.Fab")
        (effects (font (size 1 1) (thickness 0.15)) (justify mirror))
    )
    (fp_text user "License: Apache-2.0" (at -0.939 -5.799 270) (layer "B.Fab") hide
        (effects (font (size 0.7 0.7) (thickness 0.15)) (justify left bottom mirror))
    )
    (fp_text user "Author: Antmicro" (at -0.939 -3.399 270) (layer "B.Fab") hide
        (effects (font (size 0.7 0.7) (thickness 0.15)) (justify left bottom mirror))
    )
    (fp_text user "${REFERENCE}" (at 0 0 90) (layer "B.Fab")
        (effects (font (size 0.25 0.25) (thickness 0.04)) (justify mirror))
    )
    (fp_rect (start -0.925 0.47) (end 0.925 -0.47)
      (stroke (width 0.05) (type default)) (fill none) (layer "B.CrtYd"))
    (fp_line (start -0.494 -0.248) (end -0.494 0.25)
      (stroke (width 0.15) (type solid)) (layer "B.Fab"))
    (fp_line (start -0.494 0.25) (end 0.504 0.25)
      (stroke (width 0.15) (type solid)) (layer "B.Fab"))
    (fp_line (start 0.504 -0.248) (end -0.494 -0.248)
      (stroke (width 0.15) (type solid)) (layer "B.Fab"))
    (fp_line (start 0.504 0.25) (end 0.504 -0.248)
      (stroke (width 0.15) (type solid)) (layer "B.Fab"))
    (pad "1" smd roundrect (at -0.48 0 90) (size 0.59 0.64) (layers "B.Cu" "B.Paste" "B.Mask") (roundrect_rratio 0.25)
      (net 2 "VCC3V3") (pintype "passive"))
    (pad "2" smd roundrect (at 0.48 0 90) (size 0.59 0.64) (layers "B.Cu" "B.Paste" "B.Mask") (roundrect_rratio 0.25)
      (net 1 "GND") (pintype "passive"))
  )
	(footprint "antmicro-footprints:C_0402_1005Metric" (layer "B.Cu")
    (at 97.6 116.1 180)
    (descr "Capacitor SMD 0402")
    (tags "capacitor SMD 0402")
    (property "Author" "Antmicro")
    (property "Dielectric" "")
    (property "License" "Apache-2.0")
    (property "MPN" "C1005X5R1E474M050BB")
    (property "Manufacturer" "TDK")
    (property "Public" "False")
    (property "Sheetfile" "fpga-banks.kicad_sch")
    (property "Sheetname" "FPGA banks")
    (property "Val" "470n")
    (property "Voltage" "")
    (property "ki_description" "SMD Multilayer Ceramic Capacitor, 0.47 µF, 25 V, 0402 [1005 Metric], ± 20%, X5R, C")
    (property "ki_keywords" "0402, SMT, CAPACITOR, PASSIVE, CERAMIC, MLCC")
    (attr smd)
    (fp_text reference "C236" (at 2.4 0.2) (layer "B.SilkS")
        (effects (font (size 0.7 0.7) (thickness 0.127)) (justify mirror))
    )
    (fp_text value "C_470n_0402" (at 0 -1.17) (layer "B.Fab")
        (effects (font (size 1 1) (thickness 0.15)) (justify mirror))
    )
    (fp_text user "Author: Antmicro" (at -0.939 -3.399) (layer "B.Fab") hide
        (effects (font (size 0.7 0.7) (thickness 0.15)) (justify left bottom mirror))
    )
    (fp_text user "${REFERENCE}" (at 0 0) (layer "B.Fab")
        (effects (font (size 0.25 0.25) (thickness 0.04)) (justify mirror))
    )
    (fp_text user "License: Apache-2.0" (at -0.939 -5.799) (layer "B.Fab") hide
        (effects (font (size 0.7 0.7) (thickness 0.15)) (justify left bottom mirror))
    )
    (fp_rect (start -0.925 0.47) (end 0.925 -0.47)
      (stroke (width 0.05) (type default)) (fill none) (layer "B.CrtYd"))
    (fp_line (start -0.494 -0.248) (end -0.494 0.25)
      (stroke (width 0.15) (type solid)) (layer "B.Fab"))
    (fp_line (start -0.494 0.25) (end 0.504 0.25)
      (stroke (width 0.15) (type solid)) (layer "B.Fab"))
    (fp_line (start 0.504 -0.248) (end -0.494 -0.248)
      (stroke (width 0.15) (type solid)) (layer "B.Fab"))
    (fp_line (start 0.504 0.25) (end 0.504 -0.248)
      (stroke (width 0.15) (type solid)) (layer "B.Fab"))
    (pad "1" smd roundrect (at -0.48 0 180) (size 0.59 0.64) (layers "B.Cu" "B.Paste" "B.Mask") (roundrect_rratio 0.25)
      (net 2 "VCC3V3") (pintype "passive"))
    (pad "2" smd roundrect (at 0.48 0 180) (size 0.59 0.64) (layers "B.Cu" "B.Paste" "B.Mask") (roundrect_rratio 0.25)
      (net 1 "GND") (pintype "passive"))
  )
	(footprint "antmicro-footprints:C_0402_1005Metric" (layer "B.Cu")
    (at 97.6 119.207142 180)
    (descr "Capacitor SMD 0402")
    (tags "capacitor SMD 0402")
    (property "Author" "Antmicro")
    (property "Dielectric" "")
    (property "License" "Apache-2.0")
    (property "MPN" "C1005X5R1E474M050BB")
    (property "Manufacturer" "TDK")
    (property "Public" "False")
    (property "Sheetfile" "fpga-banks.kicad_sch")
    (property "Sheetname" "FPGA banks")
    (property "Val" "470n")
    (property "Voltage" "")
    (property "ki_description" "SMD Multilayer Ceramic Capacitor, 0.47 µF, 25 V, 0402 [1005 Metric], ± 20%, X5R, C")
    (property "ki_keywords" "0402, SMT, CAPACITOR, PASSIVE, CERAMIC, MLCC")
    (attr smd)
    (fp_text reference "C237" (at 2.4 0.207142) (layer "B.SilkS")
        (effects (font (size 0.7 0.7) (thickness 0.127)) (justify mirror))
    )
    (fp_text value "C_470n_0402" (at 0 -1.17) (layer "B.Fab")
        (effects (font (size 1 1) (thickness 0.15)) (justify mirror))
    )
    (fp_text user "${REFERENCE}" (at 0 0) (layer "B.Fab")
        (effects (font (size 0.25 0.25) (thickness 0.04)) (justify mirror))
    )
    (fp_text user "Author: Antmicro" (at -0.939 -3.399) (layer "B.Fab") hide
        (effects (font (size 0.7 0.7) (thickness 0.15)) (justify left bottom mirror))
    )
    (fp_text user "License: Apache-2.0" (at -0.939 -5.799) (layer "B.Fab") hide
        (effects (font (size 0.7 0.7) (thickness 0.15)) (justify left bottom mirror))
    )
    (fp_rect (start -0.925 0.47) (end 0.925 -0.47)
      (stroke (width 0.05) (type default)) (fill none) (layer "B.CrtYd"))
    (fp_line (start -0.494 -0.248) (end -0.494 0.25)
      (stroke (width 0.15) (type solid)) (layer "B.Fab"))
    (fp_line (start -0.494 0.25) (end 0.504 0.25)
      (stroke (width 0.15) (type solid)) (layer "B.Fab"))
    (fp_line (start 0.504 -0.248) (end -0.494 -0.248)
      (stroke (width 0.15) (type solid)) (layer "B.Fab"))
    (fp_line (start 0.504 0.25) (end 0.504 -0.248)
      (stroke (width 0.15) (type solid)) (layer "B.Fab"))
    (pad "1" smd roundrect (at -0.48 0 180) (size 0.59 0.64) (layers "B.Cu" "B.Paste" "B.Mask") (roundrect_rratio 0.25)
      (net 2 "VCC3V3") (pintype "passive"))
    (pad "2" smd roundrect (at 0.48 0 180) (size 0.59 0.64) (layers "B.Cu" "B.Paste" "B.Mask") (roundrect_rratio 0.25)
      (net 1 "GND") (pintype "passive"))
  )
)
